FILE_TYPE = MULTI_PHYS_TABLE;

PART 'IS32FL3207_QWLA3_TR_QFN29'
CLASS = IC

{========================================================================================}
: CLS_PN          | VALUE             	   =  JEDEC_TYPE                      	| ALT_SYMBOLS                       | DESCRIPTION                                    			| CPN_STATUS;
{========================================================================================}
 'A223-00002-FB'  |'IS32FL3207-QWLA3-TR'   = 'QFN29_197_P0197_TR115SQ_V1'  		|'(QFN29_197_P0197_TR115SQ_V1)'  	|'IC,18-CHANNEL LED DRIVER WITH 16-BIT PWM,WFQFN-28'       	| ''

END_PART

END.

